(kicad_pcb
	(version 20260206)
	(generator "pcbnew")
	(generator_version "10.0")
	(general
		(thickness 1.6)
		(legacy_teardrops no)
	)
	(paper "A4")
	(title_block
		(title "Bryce Canyon_IOM_M2_16342-2_OCP.brd")
		(comment 1 "Bryce Canyon / footprints 1027-1034 of 1146")
	)
	(layers
		(0 "F.Cu" signal "TOP")
		(4 "In1.Cu" signal "L2GND")
		(6 "In2.Cu" signal "L3")
		(8 "In3.Cu" signal "L4VCC")
		(10 "In4.Cu" signal "L5VCC")
		(12 "In5.Cu" signal "L6")
		(14 "In6.Cu" signal "L7GND")
		(2 "B.Cu" signal "BOTTOM")
		(9 "F.Adhes" user "F.Adhesive")
		(11 "B.Adhes" user "B.Adhesive")
		(13 "F.Paste" user "Package Geometry/Pastemask Top")
		(15 "B.Paste" user "Package Geometry/Pastemask Bottom")
		(5 "F.SilkS" user "Ref Des/Silkscreen Top")
		(7 "B.SilkS" user "Ref Des/Silkscreen Bottom")
		(1 "F.Mask" user "Board Geometry/Soldermask Top")
		(3 "B.Mask" user "Board Geometry/Soldermask Bottom")
		(17 "Dwgs.User" user "User.Drawings")
		(19 "Cmts.User" user "User.Comments")
		(21 "Eco1.User" user "User.Eco1")
		(23 "Eco2.User" user "User.Eco2")
		(25 "Edge.Cuts" user "Board Geometry/Outline")
		(27 "Margin" user)
		(31 "F.CrtYd" user "Package Geometry/Place Bound Top")
		(29 "B.CrtYd" user "Package Geometry/Place Bound Bottom")
		(35 "F.Fab" user "Ref Des/Assembly Top")
		(33 "B.Fab" user "Ref Des/Assembly Bottom")
	)
	(footprint ""
		(layer "B.Cu")
		(at 89.281 -148.79066)
		(property "Reference" "R96"
			(at 0 0 0)
			(layer "B.SilkS")
			(hide yes)
			(effects
				(font
					(size 1.27 1.27)
				)
				(justify mirror)
			)
		)
		(property "Value" "0R2J-2-GP"
			(at -0.064008 -3.993896 0)
			(unlocked yes)
			(layer "B.Fab")
			(hide yes)
			(effects
				(font
					(size 1.016 1.016)
					(thickness 0.1524)
				)
				(justify mirror)
			)
		)
		(property "Device Type" "R402H16"
			(at -0.064008 -5.517896 0)
			(unlocked yes)
			(layer "B.Fab")
			(hide yes)
			(effects
				(font
					(size 1.016 1.016)
					(thickness 0.1524)
				)
				(justify mirror)
			)
		)
		(duplicate_pad_numbers_are_jumpers no)
		(fp_line
			(start -0.508 -0.9398)
			(end 0.508 -0.9398)
			(stroke
				(width 0.1524)
				(type default)
			)
			(layer "B.SilkS")
		)
		(fp_line
			(start 0.508 -0.9398)
			(end 0.508 0.9398)
			(stroke
				(width 0.1524)
				(type default)
			)
			(layer "B.SilkS")
		)
		(fp_rect
			(start 0.508 0.9398)
			(end -0.508 -0.9398)
			(stroke
				(width 0)
				(type default)
			)
			(fill no)
			(layer "B.CrtYd")
		)
		(fp_rect
			(start 0.508 0.9398)
			(end -0.508 -0.9398)
			(stroke
				(width 0)
				(type default)
			)
			(fill no)
			(layer "B.Fab")
		)
		(pad "1" smd custom
			(at 0 -0.4445 180)
			(size 0.1397 0.1397)
			(layers "B.Cu" "B.Mask" "B.Paste")
			(net "I2C_BMC_COMP_SDA_R")
			(options
				(clearance outline)
				(anchor circle)
			)
			(primitives
				(gr_poly
					(pts
						(arc
							(start -0.1778 0.2794)
							(mid -0.249642 0.249642)
							(end -0.2794 0.1778)
						)
						(arc
							(start -0.2794 -0.1778)
							(mid -0.249642 -0.249642)
							(end -0.1778 -0.2794)
						)
						(arc
							(start 0.1778 -0.2794)
							(mid 0.249642 -0.249642)
							(end 0.2794 -0.1778)
						)
						(arc
							(start 0.2794 0.1778)
							(mid 0.249642 0.249642)
							(end 0.1778 0.2794)
						)
					)
					(width 0)
					(fill yes)
				)
			)
		)
		(pad "2" smd custom
			(at 0 0.4445 180)
			(size 0.1397 0.1397)
			(layers "B.Cu" "B.Mask" "B.Paste")
			(net "I2C_BMC_COMP_SDA")
			(options
				(clearance outline)
				(anchor circle)
			)
			(primitives
				(gr_poly
					(pts
						(arc
							(start -0.1778 0.2794)
							(mid -0.249642 0.249642)
							(end -0.2794 0.1778)
						)
						(arc
							(start -0.2794 -0.1778)
							(mid -0.249642 -0.249642)
							(end -0.1778 -0.2794)
						)
						(arc
							(start 0.1778 -0.2794)
							(mid 0.249642 -0.249642)
							(end 0.2794 -0.1778)
						)
						(arc
							(start 0.2794 0.1778)
							(mid 0.249642 0.249642)
							(end 0.1778 0.2794)
						)
					)
					(width 0)
					(fill yes)
				)
			)
		)
	)
	(footprint ""
		(layer "B.Cu")
		(at 56.896 -157.734 180)
		(property "Reference" "R399"
			(at 0 0 0)
			(layer "B.SilkS")
			(hide yes)
			(effects
				(font
					(size 1.27 1.27)
				)
				(justify mirror)
			)
		)
		(property "Value" "4K7R2F-GP"
			(at -0.064008 -3.993896 180)
			(unlocked yes)
			(layer "B.Fab")
			(hide yes)
			(effects
				(font
					(size 1.016 1.016)
					(thickness 0.1524)
				)
				(justify mirror)
			)
		)
		(property "Device Type" "R402H16"
			(at -0.064008 -5.517896 180)
			(unlocked yes)
			(layer "B.Fab")
			(hide yes)
			(effects
				(font
					(size 1.016 1.016)
					(thickness 0.1524)
				)
				(justify mirror)
			)
		)
		(duplicate_pad_numbers_are_jumpers no)
		(fp_line
			(start 0.508 -0.9398)
			(end 0.508 0.9398)
			(stroke
				(width 0.1524)
				(type default)
			)
			(layer "B.SilkS")
		)
		(fp_line
			(start -0.508 -0.9398)
			(end 0.508 -0.9398)
			(stroke
				(width 0.1524)
				(type default)
			)
			(layer "B.SilkS")
		)
		(fp_rect
			(start 0.508 0.9398)
			(end -0.508 -0.9398)
			(stroke
				(width 0)
				(type default)
			)
			(fill no)
			(layer "B.CrtYd")
		)
		(fp_rect
			(start 0.508 0.9398)
			(end -0.508 -0.9398)
			(stroke
				(width 0)
				(type default)
			)
			(fill no)
			(layer "B.Fab")
		)
		(pad "1" smd custom
			(at 0 -0.4445)
			(size 0.1397 0.1397)
			(layers "B.Cu" "B.Mask" "B.Paste")
			(net "GND")
			(options
				(clearance outline)
				(anchor circle)
			)
			(primitives
				(gr_poly
					(pts
						(arc
							(start -0.1778 0.2794)
							(mid -0.249642 0.249642)
							(end -0.2794 0.1778)
						)
						(arc
							(start -0.2794 -0.1778)
							(mid -0.249642 -0.249642)
							(end -0.1778 -0.2794)
						)
						(arc
							(start 0.1778 -0.2794)
							(mid 0.249642 -0.249642)
							(end 0.2794 -0.1778)
						)
						(arc
							(start 0.2794 0.1778)
							(mid 0.249642 0.249642)
							(end 0.1778 0.2794)
						)
					)
					(width 0)
					(fill yes)
				)
			)
		)
		(pad "2" smd custom
			(at 0 0.4445)
			(size 0.1397 0.1397)
			(layers "B.Cu" "B.Mask" "B.Paste")
			(net "MAC2_TXD3")
			(options
				(clearance outline)
				(anchor circle)
			)
			(primitives
				(gr_poly
					(pts
						(arc
							(start -0.1778 0.2794)
							(mid -0.249642 0.249642)
							(end -0.2794 0.1778)
						)
						(arc
							(start -0.2794 -0.1778)
							(mid -0.249642 -0.249642)
							(end -0.1778 -0.2794)
						)
						(arc
							(start 0.1778 -0.2794)
							(mid 0.249642 -0.249642)
							(end 0.2794 -0.1778)
						)
						(arc
							(start 0.2794 0.1778)
							(mid 0.249642 0.249642)
							(end 0.1778 0.2794)
						)
					)
					(width 0)
					(fill yes)
				)
			)
		)
	)
	(footprint ""
		(layer "B.Cu")
		(at 83.800442 -147.307046 90)
		(property "Reference" "C485"
			(at 0 0 90)
			(layer "B.SilkS")
			(hide yes)
			(effects
				(font
					(size 1.27 1.27)
				)
				(justify mirror)
			)
		)
		(property "Value" "SCD1U16V2KX-3GP"
			(at -1.1811 -2.7051 90)
			(unlocked yes)
			(layer "B.Fab")
			(hide yes)
			(effects
				(font
					(size 1.016 1.016)
					(thickness 0.1524)
				)
				(justify mirror)
			)
		)
		(property "Device Type" "C402H22"
			(at -1.1811 -4.2291 90)
			(unlocked yes)
			(layer "B.Fab")
			(hide yes)
			(effects
				(font
					(size 1.016 1.016)
					(thickness 0.1524)
				)
				(justify mirror)
			)
		)
		(duplicate_pad_numbers_are_jumpers no)
		(fp_rect
			(start 0.4318 0.9525)
			(end -0.4318 -0.9525)
			(stroke
				(width 0)
				(type default)
			)
			(fill no)
			(layer "B.CrtYd")
		)
		(fp_rect
			(start 0.4318 0.9525)
			(end -0.4318 -0.9525)
			(stroke
				(width 0)
				(type default)
			)
			(fill no)
			(layer "B.Fab")
		)
		(pad "1" smd custom
			(at 0 -0.4445 270)
			(size 0.1524 0.1524)
			(layers "B.Cu" "B.Mask" "B.Paste")
			(net "P3V3_STBY")
			(options
				(clearance outline)
				(anchor circle)
			)
			(primitives
				(gr_poly
					(pts
						(arc
							(start 0.3048 0.2032)
							(mid 0.275042 0.275042)
							(end 0.2032 0.3048)
						)
						(arc
							(start -0.2032 0.3048)
							(mid -0.275042 0.275042)
							(end -0.3048 0.2032)
						)
						(arc
							(start -0.3048 -0.2032)
							(mid -0.275042 -0.275042)
							(end -0.2032 -0.3048)
						)
						(arc
							(start 0.2032 -0.3048)
							(mid 0.275042 -0.275042)
							(end 0.3048 -0.2032)
						)
					)
					(width 0)
					(fill yes)
				)
			)
		)
		(pad "2" smd custom
			(at 0 0.4445 270)
			(size 0.1524 0.1524)
			(layers "B.Cu" "B.Mask" "B.Paste")
			(net "GND")
			(options
				(clearance outline)
				(anchor circle)
			)
			(primitives
				(gr_poly
					(pts
						(arc
							(start 0.3048 0.2032)
							(mid 0.275042 0.275042)
							(end 0.2032 0.3048)
						)
						(arc
							(start -0.2032 0.3048)
							(mid -0.275042 0.275042)
							(end -0.3048 0.2032)
						)
						(arc
							(start -0.3048 -0.2032)
							(mid -0.275042 -0.275042)
							(end -0.2032 -0.3048)
						)
						(arc
							(start 0.2032 -0.3048)
							(mid 0.275042 -0.275042)
							(end 0.3048 -0.2032)
						)
					)
					(width 0)
					(fill yes)
				)
			)
		)
	)
	(footprint ""
		(layer "B.Cu")
		(at 56.850026 -161.083752 90)
		(property "Reference" "C123"
			(at 0 0 90)
			(layer "B.SilkS")
			(hide yes)
			(effects
				(font
					(size 1.27 1.27)
				)
				(justify mirror)
			)
		)
		(property "Value" "SCD1U25V2KX-2-GP"
			(at -1.1811 -2.7051 90)
			(unlocked yes)
			(layer "B.Fab")
			(hide yes)
			(effects
				(font
					(size 1.016 1.016)
					(thickness 0.1524)
				)
				(justify mirror)
			)
		)
		(property "Device Type" "C402H22"
			(at -1.1811 -4.2291 90)
			(unlocked yes)
			(layer "B.Fab")
			(hide yes)
			(effects
				(font
					(size 1.016 1.016)
					(thickness 0.1524)
				)
				(justify mirror)
			)
		)
		(duplicate_pad_numbers_are_jumpers no)
		(fp_rect
			(start 0.4318 0.9525)
			(end -0.4318 -0.9525)
			(stroke
				(width 0)
				(type default)
			)
			(fill no)
			(layer "B.CrtYd")
		)
		(fp_rect
			(start 0.4318 0.9525)
			(end -0.4318 -0.9525)
			(stroke
				(width 0)
				(type default)
			)
			(fill no)
			(layer "B.Fab")
		)
		(pad "1" smd custom
			(at 0 -0.4445 270)
			(size 0.1524 0.1524)
			(layers "B.Cu" "B.Mask" "B.Paste")
			(net "ADC_P5V_STBY")
			(options
				(clearance outline)
				(anchor circle)
			)
			(primitives
				(gr_poly
					(pts
						(arc
							(start 0.3048 0.2032)
							(mid 0.275042 0.275042)
							(end 0.2032 0.3048)
						)
						(arc
							(start -0.2032 0.3048)
							(mid -0.275042 0.275042)
							(end -0.3048 0.2032)
						)
						(arc
							(start -0.3048 -0.2032)
							(mid -0.275042 -0.275042)
							(end -0.2032 -0.3048)
						)
						(arc
							(start 0.2032 -0.3048)
							(mid 0.275042 -0.275042)
							(end 0.3048 -0.2032)
						)
					)
					(width 0)
					(fill yes)
				)
			)
		)
		(pad "2" smd custom
			(at 0 0.4445 270)
			(size 0.1524 0.1524)
			(layers "B.Cu" "B.Mask" "B.Paste")
			(net "GND")
			(options
				(clearance outline)
				(anchor circle)
			)
			(primitives
				(gr_poly
					(pts
						(arc
							(start 0.3048 0.2032)
							(mid 0.275042 0.275042)
							(end 0.2032 0.3048)
						)
						(arc
							(start -0.2032 0.3048)
							(mid -0.275042 0.275042)
							(end -0.3048 0.2032)
						)
						(arc
							(start -0.3048 -0.2032)
							(mid -0.275042 -0.275042)
							(end -0.2032 -0.3048)
						)
						(arc
							(start 0.2032 -0.3048)
							(mid 0.275042 -0.275042)
							(end 0.3048 -0.2032)
						)
					)
					(width 0)
					(fill yes)
				)
			)
		)
	)
	(footprint ""
		(layer "B.Cu")
		(at 37.2618 -134.2136 180)
		(property "Reference" "R277"
			(at 0 0 0)
			(layer "B.SilkS")
			(hide yes)
			(effects
				(font
					(size 1.27 1.27)
				)
				(justify mirror)
			)
		)
		(property "Value" "33R2F-3-GP"
			(at -0.064008 -3.993896 180)
			(unlocked yes)
			(layer "B.Fab")
			(hide yes)
			(effects
				(font
					(size 1.016 1.016)
					(thickness 0.1524)
				)
				(justify mirror)
			)
		)
		(property "Device Type" "R402H16"
			(at -0.064008 -5.517896 180)
			(unlocked yes)
			(layer "B.Fab")
			(hide yes)
			(effects
				(font
					(size 1.016 1.016)
					(thickness 0.1524)
				)
				(justify mirror)
			)
		)
		(duplicate_pad_numbers_are_jumpers no)
		(fp_line
			(start 0.508 -0.9398)
			(end 0.508 0.9398)
			(stroke
				(width 0.1524)
				(type default)
			)
			(layer "B.SilkS")
		)
		(fp_line
			(start -0.508 -0.9398)
			(end 0.508 -0.9398)
			(stroke
				(width 0.1524)
				(type default)
			)
			(layer "B.SilkS")
		)
		(fp_rect
			(start 0.508 0.9398)
			(end -0.508 -0.9398)
			(stroke
				(width 0)
				(type default)
			)
			(fill no)
			(layer "B.CrtYd")
		)
		(fp_rect
			(start 0.508 0.9398)
			(end -0.508 -0.9398)
			(stroke
				(width 0)
				(type default)
			)
			(fill no)
			(layer "B.Fab")
		)
		(pad "1" smd custom
			(at 0 -0.4445)
			(size 0.1397 0.1397)
			(layers "B.Cu" "B.Mask" "B.Paste")
			(net "FLA_CS_1_R")
			(options
				(clearance outline)
				(anchor circle)
			)
			(primitives
				(gr_poly
					(pts
						(arc
							(start -0.1778 0.2794)
							(mid -0.249642 0.249642)
							(end -0.2794 0.1778)
						)
						(arc
							(start -0.2794 -0.1778)
							(mid -0.249642 -0.249642)
							(end -0.1778 -0.2794)
						)
						(arc
							(start 0.1778 -0.2794)
							(mid 0.249642 -0.249642)
							(end 0.2794 -0.1778)
						)
						(arc
							(start 0.2794 0.1778)
							(mid 0.249642 0.249642)
							(end 0.1778 0.2794)
						)
					)
					(width 0)
					(fill yes)
				)
			)
		)
		(pad "2" smd custom
			(at 0 0.4445)
			(size 0.1397 0.1397)
			(layers "B.Cu" "B.Mask" "B.Paste")
			(net "FLA_CS_1")
			(options
				(clearance outline)
				(anchor circle)
			)
			(primitives
				(gr_poly
					(pts
						(arc
							(start -0.1778 0.2794)
							(mid -0.249642 0.249642)
							(end -0.2794 0.1778)
						)
						(arc
							(start -0.2794 -0.1778)
							(mid -0.249642 -0.249642)
							(end -0.1778 -0.2794)
						)
						(arc
							(start 0.1778 -0.2794)
							(mid 0.249642 -0.249642)
							(end 0.2794 -0.1778)
						)
						(arc
							(start 0.2794 0.1778)
							(mid 0.249642 0.249642)
							(end 0.1778 0.2794)
						)
					)
					(width 0)
					(fill yes)
				)
			)
		)
	)
	(footprint ""
		(layer "B.Cu")
		(at 46.9138 -149.6822 180)
		(property "Reference" "R707"
			(at 0 0 0)
			(layer "B.SilkS")
			(hide yes)
			(effects
				(font
					(size 1.27 1.27)
				)
				(justify mirror)
			)
		)
		(property "Value" "4K7R2F-GP"
			(at -0.064008 -3.993896 180)
			(unlocked yes)
			(layer "B.Fab")
			(hide yes)
			(effects
				(font
					(size 1.016 1.016)
					(thickness 0.1524)
				)
				(justify mirror)
			)
		)
		(property "Device Type" "R402H16"
			(at -0.064008 -5.517896 180)
			(unlocked yes)
			(layer "B.Fab")
			(hide yes)
			(effects
				(font
					(size 1.016 1.016)
					(thickness 0.1524)
				)
				(justify mirror)
			)
		)
		(duplicate_pad_numbers_are_jumpers no)
		(fp_line
			(start 0.508 -0.9398)
			(end 0.508 0.9398)
			(stroke
				(width 0.1524)
				(type default)
			)
			(layer "B.SilkS")
		)
		(fp_line
			(start -0.508 -0.9398)
			(end 0.508 -0.9398)
			(stroke
				(width 0.1524)
				(type default)
			)
			(layer "B.SilkS")
		)
		(fp_rect
			(start 0.508 0.9398)
			(end -0.508 -0.9398)
			(stroke
				(width 0)
				(type default)
			)
			(fill no)
			(layer "B.CrtYd")
		)
		(fp_rect
			(start 0.508 0.9398)
			(end -0.508 -0.9398)
			(stroke
				(width 0)
				(type default)
			)
			(fill no)
			(layer "B.Fab")
		)
		(pad "1" smd custom
			(at 0 -0.4445)
			(size 0.1397 0.1397)
			(layers "B.Cu" "B.Mask" "B.Paste")
			(net "P3V3_STBY")
			(options
				(clearance outline)
				(anchor circle)
			)
			(primitives
				(gr_poly
					(pts
						(arc
							(start -0.1778 0.2794)
							(mid -0.249642 0.249642)
							(end -0.2794 0.1778)
						)
						(arc
							(start -0.2794 -0.1778)
							(mid -0.249642 -0.249642)
							(end -0.1778 -0.2794)
						)
						(arc
							(start 0.1778 -0.2794)
							(mid 0.249642 -0.249642)
							(end 0.2794 -0.1778)
						)
						(arc
							(start 0.2794 0.1778)
							(mid 0.249642 0.249642)
							(end 0.1778 0.2794)
						)
					)
					(width 0)
					(fill yes)
				)
			)
		)
		(pad "2" smd custom
			(at 0 0.4445)
			(size 0.1397 0.1397)
			(layers "B.Cu" "B.Mask" "B.Paste")
			(net "IOM_TYPE0")
			(options
				(clearance outline)
				(anchor circle)
			)
			(primitives
				(gr_poly
					(pts
						(arc
							(start -0.1778 0.2794)
							(mid -0.249642 0.249642)
							(end -0.2794 0.1778)
						)
						(arc
							(start -0.2794 -0.1778)
							(mid -0.249642 -0.249642)
							(end -0.1778 -0.2794)
						)
						(arc
							(start 0.1778 -0.2794)
							(mid 0.249642 -0.249642)
							(end 0.2794 -0.1778)
						)
						(arc
							(start 0.2794 0.1778)
							(mid 0.249642 0.249642)
							(end 0.1778 0.2794)
						)
					)
					(width 0)
					(fill yes)
				)
			)
		)
	)
	(footprint ""
		(layer "B.Cu")
		(at 57.963054 -130.700272)
		(property "Reference" "C116"
			(at 0 0 0)
			(layer "B.SilkS")
			(hide yes)
			(effects
				(font
					(size 1.27 1.27)
				)
				(justify mirror)
			)
		)
		(property "Value" "SC4D7U25V5KX-1-GP"
			(at 0.0762 -6.1214 0)
			(unlocked yes)
			(layer "B.Fab")
			(hide yes)
			(effects
				(font
					(size 1.016 1.016)
					(thickness 0.1524)
				)
				(justify mirror)
			)
		)
		(property "Device Type" "C805H58"
			(at 0.0762 -8.1534 0)
			(unlocked yes)
			(layer "B.Fab")
			(hide yes)
			(effects
				(font
					(size 1.016 1.016)
					(thickness 0.1524)
				)
				(justify mirror)
			)
		)
		(duplicate_pad_numbers_are_jumpers no)
		(fp_line
			(start -0.635 0)
			(end 0.635 0)
			(stroke
				(width 0.508)
				(type default)
			)
			(layer "B.SilkS")
		)
		(fp_rect
			(start 0.9652 1.778)
			(end -0.9652 -1.778)
			(stroke
				(width 0)
				(type default)
			)
			(fill no)
			(layer "B.CrtYd")
		)
		(fp_poly
			(pts
				(xy 0.9652 -1.778) (xy -0.9652 -1.778) (xy -0.9652 1.778) (xy 0.9652 1.778)
			)
			(stroke
				(width 0)
				(type default)
			)
			(fill no)
			(layer "B.Fab")
		)
		(pad "1" smd rect
			(at 0 -0.9652 180)
			(size 1.397 1.143)
			(layers "B.Cu" "B.Mask" "B.Paste")
			(net "P1V15_STBY")
		)
		(pad "2" smd rect
			(at 0 0.9652 180)
			(size 1.397 1.143)
			(layers "B.Cu" "B.Mask" "B.Paste")
			(net "GND")
		)
	)
	(footprint ""
		(layer "B.Cu")
		(at 45.3644 -122.8852)
		(property "Reference" "TP19"
			(at 0 0 0)
			(layer "B.SilkS")
			(hide yes)
			(effects
				(font
					(size 1.27 1.27)
				)
				(justify mirror)
			)
		)
		(property "Value" "TPAD32-GP"
			(at 0.0508 -1.6764 0)
			(unlocked yes)
			(layer "B.Fab")
			(hide yes)
			(effects
				(font
					(size 1.016 1.016)
					(thickness 0.1524)
				)
				(justify mirror)
			)
		)
		(property "Device Type" "TPAD32"
			(at 0.0508 -3.2004 0)
			(unlocked yes)
			(layer "B.Fab")
			(hide yes)
			(effects
				(font
					(size 1.016 1.016)
					(thickness 0.1524)
				)
				(justify mirror)
			)
		)
		(duplicate_pad_numbers_are_jumpers no)
		(fp_poly
			(pts
				(arc
					(start 0.4064 0)
					(mid -0.4064 0)
					(end 0.4064 0)
				)
			)
			(stroke
				(width 0)
				(type default)
			)
			(fill no)
			(layer "B.CrtYd")
		)
		(fp_poly
			(pts
				(arc
					(start 0.7112 0)
					(mid -0.7112 0)
					(end 0.7112 0)
				)
			)
			(stroke
				(width 0)
				(type default)
			)
			(fill no)
			(layer "B.Fab")
		)
		(pad "1" smd circle
			(at 0 0 180)
			(size 0.8128 0.8128)
			(layers "B.Cu" "B.Mask" "B.Paste")
			(net "TEMP_3_ALERT")
		)
	)
)
